FILE_TYPE = CONNECTIVITY;
{Allegro Design Entry HDL 17.2-2016 S081 (4005846) 1/11/2022}
"PAGE_NUMBER" = 109;
0"NC";
END.
